FILE_TYPE = CONNECTIVITY;
{Allegro Design Entry HDL 17.2-2016 S081 (4005846) 1/11/2022}
"PAGE_NUMBER" = 185;
0"NC";
1"PVNN_TERM_CPU0\g";
2"PVNN_TERM_CPU0\g";
3"P3V3_AUX\g";
4"P3V3_AUX\g";
5"GND\g";
6"GND\g";
7"GND\g";
8"GND\g";
9"GND\g";
10"PECI_PCH_B1"CDS_PHYS_NET_NAME"IRQ_LPC_SERIRQ_ESPI_CS1_N";
11"PECI_BMC"CDS_PHYS_NET_NAME"IRQ_LPC_SERIRQ_ESPI_CS1_N";
12"PECI_CPU_GTL"CDS_PHYS_NET_NAME"IRQ_LPC_SERIRQ_ESPI_CS1_N";
13"PECI_PCH_R"CDS_PHYS_NET_NAME"IRQ_LPC_SERIRQ_ESPI_CS1_N";
14"PECI_PCH"CDS_PHYS_NET_NAME"IRQ_LPC_SERIRQ_ESPI_CS1_N";
15"PECI_BMC_R"CDS_PHYS_NET_NAME"IRQ_LPC_SERIRQ_ESPI_CS1_N";
16"PECI_BMC_B1"CDS_PHYS_NET_NAME"IRQ_LPC_SERIRQ_ESPI_CS1_N";
17"PECI_BMC_ME";
18"PECI_MUX_SEL_R"CDS_PHYS_NET_NAME"IRQ_LPC_SERIRQ_ESPI_CS1_N";
19"FM_PECI_MUX_SEL_N"CDS_PHYS_NET_NAME"IRQ_LPC_SERIRQ_ESPI_CS1_N";
%"UNIVERSAL_GND"
"1","(-7550,2775)","0","logical_power","I22";
;
CDS_LIB"logical_power"
HDL_POWER"GND"
ROOM"IO_SLOT";
"A"9;
%"Q_RES"
"1","(-7075,3300)","0","pure_quanta","I24";
;
PART_NUMBER"CS00002JB13"
MATERIAL"CHIP"
VALUE"0"
WATTAGE"1/16W"
TOLERANCE"5%"
PACK_TYPE"0402LF"
$LOCATION"R149"
CDS_LIB"pure_quanta"
CDS_LOCATION"R149"
$SEC"1"
CDS_SEC"1";
"B"
$PN"2"10;
"A"
$PN"1"13;
%"Q_RES"
"2","(-7700,3625)","0","pure_quanta","I26";
;
PART_NUMBER"CS24752FB03"
TOLERANCE"1%"
MATERIAL"EMPTY"
VALUE"4.75K"
WATTAGE"1/16W"
PACK_TYPE"0402LF"
$LOCATION"R145"
CDS_LIB"pure_quanta"
CDS_LOCATION"R145"
$SEC"1"
CDS_SEC"1";
"A"
$PN"1"1;
"B"
$PN"2"13;
%"UNIVERSAL_POWER"
"1","(-7700,3875)","0","logical_power","I27";
;
HDL_POWER"PVNN_TERM_CPU0"
CDS_LIB"logical_power";
"A"1;
%"UNIVERSAL_GND"
"1","(-7525,4100)","0","logical_power","I28";
;
CDS_LIB"logical_power"
HDL_POWER"GND"
ROOM"IO_SLOT";
"A"8;
%"Q_RES"
"2","(-7675,4950)","0","pure_quanta","I30";
;
PART_NUMBER"CS24752FB03"
TOLERANCE"1%"
VALUE"4.75K"
MATERIAL"EMPTY"
WATTAGE"1/16W"
PACK_TYPE"0402LF"
$LOCATION"R146"
CDS_LIB"pure_quanta"
CDS_LOCATION"R146"
$SEC"1"
CDS_SEC"1";
"A"
$PN"1"2;
"B"
$PN"2"15;
%"UNIVERSAL_POWER"
"1","(-7675,5200)","0","logical_power","I31";
;
HDL_POWER"PVNN_TERM_CPU0"
CDS_LIB"logical_power";
"A"2;
%"Q_RES"
"1","(-7050,4625)","0","pure_quanta","I32";
;
PART_NUMBER"CS00002JB13"
TOLERANCE"5%"
MATERIAL"CHIP"
VALUE"0"
WATTAGE"1/16W"
PACK_TYPE"0402LF"
$LOCATION"R1297"
CDS_LIB"pure_quanta"
CDS_LOCATION"R1297"
$SEC"1"
CDS_SEC"1";
"B"
$PN"2"16;
"A"
$PN"1"15;
%"UNIVERSAL_GND"
"1","(-5900,3500)","0","logical_power","I34";
;
CDS_LIB"logical_power"
HDL_POWER"GND"
ROOM"IO_SLOT";
"A"7;
%"NC7SB3157"
"1","(-5450,4075)","0","pure_quanta","I35";
;
PART_NUMBER"ALSB3157000"
VALUE"NC7SB3157P6X"
MATERIAL"IC"
$LOCATION"U142"
MANUF_PN"NC7SB3157P6X"
CDS_LMAN_SYM_OUTLINE"-150,50,150,-150"
CDS_LIB"pure_quanta"
PACK_TYPE"SMLF"
SEC_TYPE"SMLF"
CDS_LOCATION"U142"
SEC"1";
"S"
$PN"6"18;
"B0"
$PN"3"10;
"B1"
$PN"1"16;
"VCC"
$PN"5"3;
"GND"
$PN"2"7;
"A"
$PN"4"12;
%"Q_CAP"
"1","(-4925,4475)","0","pure_quanta","I36";
;
PART_NUMBER"CH5104KEB02"
TOLERANCE"10%"
PACK_TYPE"C0402"
MATERIAL"X6S"
VALUE"1UF"
VOLTAGE"25V"
$LOCATION"C1612"
CDS_LIB"pure_quanta"
CDS_LOCATION"C1612"
$SEC"1"
CDS_SEC"1";
"B"
$PN"2"6;
"A"
$PN"1"3;
%"UNIVERSAL_POWER"
"1","(-5025,4750)","0","logical_power","I37";
;
HDL_POWER"P3V3_AUX"
CDS_LIB"logical_power";
"A"3;
%"UNIVERSAL_GND"
"1","(-4925,4275)","0","logical_power","I38";
;
CDS_LIB"logical_power"
HDL_POWER"GND"
ROOM"IO_SLOT";
"A"6;
%"Q_RES"
"2","(-4625,4350)","0","pure_quanta","I39";
;
PART_NUMBER"CS24752FB03"
MATERIAL"CHIP"
WATTAGE"1/16W"
VALUE"4.75K"
TOLERANCE"1%"
PACK_TYPE"0402LF"
$LOCATION"R2253"
CDS_LIB"pure_quanta"
CDS_LOCATION"R2253"
$SEC"1"
CDS_SEC"1";
"A"
$PN"1"4;
"B"
$PN"2"18;
%"UNIVERSAL_POWER"
"1","(-4625,4625)","0","logical_power","I40";
;
HDL_POWER"P3V3_AUX"
CDS_LIB"logical_power";
"A"4;
%"Q_RES"
"1","(-3675,4075)","0","pure_quanta","I41";
;
PART_NUMBER"CS00002JB13"
PACK_TYPE"0402LF"
MATERIAL"CHIP"
TOLERANCE"5%"
VALUE"0"
WATTAGE"1/16W"
$LOCATION"R2255"
CDS_LIB"pure_quanta"
CDS_LOCATION"R2255"
$SEC"1"
CDS_SEC"1";
"B"
$PN"2"19;
"A"
$PN"1"18;
%"Q_RES"
"2","(-4675,3825)","0","pure_quanta","I42";
;
PART_NUMBER"CS41002FB09"
TOLERANCE"1%"
WATTAGE"1/16W"
MATERIAL"EMPTY"
VALUE"100K"
PACK_TYPE"0402LF"
$LOCATION"R2252"
CDS_LIB"pure_quanta"
CDS_LOCATION"R2252"
$SEC"1"
CDS_SEC"1";
"A"
$PN"1"18;
"B"
$PN"2"5;
%"UNIVERSAL_GND"
"1","(-4675,3575)","0","logical_power","I43";
;
CDS_LIB"logical_power"
HDL_POWER"GND"
ROOM"IO_SLOT";
"A"5;
%"Q_RES"
"1","(-4275,2125)","0","pure_quanta","I45";
;
PART_NUMBER"CS00002JB13"
PACK_TYPE"0402LF"
VALUE"0"
MATERIAL"EMPTY"
TOLERANCE"5%"
WATTAGE"1/16W"
$LOCATION"R3064"
CDS_LIB"pure_quanta"
CDS_LOCATION"R3064"
$SEC"1"
CDS_SEC"1";
"B"
$PN"2"17;
"A"
$PN"1"12;
%"Q_RES"
"1","(-8800,3300)","0","pure_quanta","I47";
;
PART_NUMBER"CS04992FB07"
MATERIAL"CHIP"
VALUE"49.9"
TOLERANCE"1%"
WATTAGE"1/16W"
PACK_TYPE"0402LF"
LOCATION"R143"
CDS_LIB"pure_quanta"
$SEC"1"
CDS_SEC"1";
"B"
$PN"2"13;
"A"
$PN"1"14;
%"Q_RES"
"2","(-7525,4375)","0","pure_quanta","I49";
;
PART_NUMBER"CS31002FB08"
WATTAGE"1/16W"
TOLERANCE"1%"
MATERIAL"EMPTY"
PACK_TYPE"0402LF"
VALUE"10K"
LOCATION"R148"
CDS_LIB"pure_quanta"
$SEC"1"
CDS_SEC"1";
"A"
$PN"1"15;
"B"
$PN"2"8;
%"Q_RES"
"2","(-7550,3050)","0","pure_quanta","I50";
;
PART_NUMBER"CS31002FB08"
PACK_TYPE"0402LF"
MATERIAL"CHIP"
WATTAGE"1/16W"
TOLERANCE"1%"
VALUE"10K"
LOCATION"R147"
CDS_LIB"pure_quanta"
$SEC"1"
CDS_SEC"1";
"A"
$PN"1"13;
"B"
$PN"2"9;
%"Q_RES"
"1","(-8800,4625)","0","pure_quanta","I51";
;
PART_NUMBER"CS00002JB13"
WATTAGE"1/16W"
PACK_TYPE"0402LF"
VALUE"0"
TOLERANCE"5%"
MATERIAL"CHIP"
LOCATION"R144"
CDS_LIB"pure_quanta"
$SEC"1"
CDS_SEC"1";
"B"
$PN"2"15;
"A"
$PN"1"11;
END.
